# S9S_MB_2U (Grand Teton) — schematic netlist excerpt (pin names and nets, part order shuffled) for the footprints in the layout excerpt that follows; sources: Cadence DE-HDL packaged netlist, KiCad conversion of 03242023_DA0F0TMBIJ0_F0T_Motherboard_J_brd_V01_OCP.brd

C542  Q_CAP  1UF 25V 10% X6S  pkg C0402  page 133 : A = P3V3_AUX ; B = GND
R942  Q_RES  10K 1% CHIP  pkg 0402LF  page 115 : A = P3V3_AUX ; B = PWRGD_FAIL_CPU0_EF_R1

(kicad_pcb
	(version 20260206)
	(generator "pcbnew")
	(generator_version "10.0")
	(general
		(thickness 1.6)
		(legacy_teardrops no)
	)
	(paper "A4")
	(title_block
		(title "03242023_DA0F0TMBIJ0_F0T_Motherboard_J_brd_V01_OCP.brd")
		(comment 1 "Grand Teton / footprints 5986-5987 of 6105")
	)
	(layers
		(0 "F.Cu" signal "TOP")
		(4 "In1.Cu" signal "GND")
		(6 "In2.Cu" signal "IN1")
		(8 "In3.Cu" signal "GND1")
		(10 "In4.Cu" signal "IN2")
		(12 "In5.Cu" signal "GND2")
		(14 "In6.Cu" signal "IN3")
		(16 "In7.Cu" signal "GND3")
		(18 "In8.Cu" signal "VCC")
		(20 "In9.Cu" signal "VCC1")
		(22 "In10.Cu" signal "GND4")
		(24 "In11.Cu" signal "IN4")
		(26 "In12.Cu" signal "GND5")
		(28 "In13.Cu" signal "IN5")
		(30 "In14.Cu" signal "GND6")
		(32 "In15.Cu" signal "IN6")
		(34 "In16.Cu" signal "GND7")
		(2 "B.Cu" signal "BOTTOM")
		(9 "F.Adhes" user "F.Adhesive")
		(11 "B.Adhes" user "B.Adhesive")
		(13 "F.Paste" user "Package Geometry/Pastemask Top")
		(15 "B.Paste" user "Package Geometry/Pastemask Bottom")
		(5 "F.SilkS" user "Ref Des/Silkscreen Top")
		(7 "B.SilkS" user "Ref Des/Silkscreen Bottom")
		(1 "F.Mask" user "Board Geometry/Soldermask Top")
		(3 "B.Mask" user "Board Geometry/Soldermask Bottom")
		(17 "Dwgs.User" user "User.Drawings")
		(19 "Cmts.User" user "User.Comments")
		(21 "Eco1.User" user "User.Eco1")
		(23 "Eco2.User" user "User.Eco2")
		(25 "Edge.Cuts" user "Board Geometry/Outline")
		(27 "Margin" user)
		(31 "F.CrtYd" user "Package Geometry/Place Bound Top")
		(29 "B.CrtYd" user "Package Geometry/Place Bound Bottom")
		(35 "F.Fab" user "Ref Des/Assembly Top")
		(33 "B.Fab" user "Ref Des/Assembly Bottom")
	)
	(footprint ""
		(layer "B.Cu")
		(at 434.089302 -318.868806 90)
		(property "Reference" "R942"
			(at 0 0 90)
			(layer "B.SilkS")
			(hide yes)
			(effects
				(font
					(size 1.27 1.27)
				)
				(justify mirror)
			)
		)
		(property "Value" ""
			(at 0 0 90)
			(layer "B.Fab")
			(effects
				(font
					(size 1.27 1.27)
				)
				(justify mirror)
			)
		)
		(duplicate_pad_numbers_are_jumpers no)
		(fp_line
			(start 0.7874 -0.4064)
			(end -0.7874 -0.4064)
			(stroke
				(width 0.1524)
				(type default)
			)
			(layer "B.SilkS")
		)
		(fp_line
			(start -0.7874 -0.4064)
			(end -0.7874 0.4064)
			(stroke
				(width 0.1524)
				(type default)
			)
			(layer "B.SilkS")
		)
		(fp_line
			(start 0.7874 0.4064)
			(end 0.7874 -0.4064)
			(stroke
				(width 0.1524)
				(type default)
			)
			(layer "B.SilkS")
		)
		(fp_line
			(start -0.7874 0.4064)
			(end 0.7874 0.4064)
			(stroke
				(width 0.1524)
				(type default)
			)
			(layer "B.SilkS")
		)
		(fp_line
			(start 0.67945 -0.305054)
			(end 0.12065 -0.305054)
			(stroke
				(width 0.1)
				(type default)
			)
			(layer "B.Fab")
		)
		(fp_line
			(start 0.12065 -0.305054)
			(end 0.12065 -0.2794)
			(stroke
				(width 0.1)
				(type default)
			)
			(layer "B.Fab")
		)
		(fp_line
			(start -0.12065 -0.3048)
			(end -0.67945 -0.3048)
			(stroke
				(width 0.1)
				(type default)
			)
			(layer "B.Fab")
		)
		(fp_line
			(start -0.67945 -0.3048)
			(end -0.67945 0.3048)
			(stroke
				(width 0.1)
				(type default)
			)
			(layer "B.Fab")
		)
		(fp_line
			(start 0.12065 -0.2794)
			(end -0.12065 -0.2794)
			(stroke
				(width 0.1)
				(type default)
			)
			(layer "B.Fab")
		)
		(fp_line
			(start -0.12065 -0.2794)
			(end -0.12065 -0.3048)
			(stroke
				(width 0.1)
				(type default)
			)
			(layer "B.Fab")
		)
		(fp_line
			(start 0.12065 0.2794)
			(end 0.12065 0.3048)
			(stroke
				(width 0.1)
				(type default)
			)
			(layer "B.Fab")
		)
		(fp_line
			(start -0.120396 0.2794)
			(end 0.12065 0.2794)
			(stroke
				(width 0.1)
				(type default)
			)
			(layer "B.Fab")
		)
		(fp_line
			(start 0.67945 0.3048)
			(end 0.67945 -0.305054)
			(stroke
				(width 0.1)
				(type default)
			)
			(layer "B.Fab")
		)
		(fp_line
			(start 0.12065 0.3048)
			(end 0.67945 0.3048)
			(stroke
				(width 0.1)
				(type default)
			)
			(layer "B.Fab")
		)
		(fp_line
			(start -0.120396 0.3048)
			(end -0.120396 0.2794)
			(stroke
				(width 0.1)
				(type default)
			)
			(layer "B.Fab")
		)
		(fp_line
			(start -0.67945 0.3048)
			(end -0.120396 0.3048)
			(stroke
				(width 0.1)
				(type default)
			)
			(layer "B.Fab")
		)
		(pad "1" smd circle
			(at 0.40005 0 270)
			(size 0 0)
			(layers "B.Cu" "B.Mask" "B.Paste")
			(net "P3V3_AUX")
		)
		(pad "2" smd circle
			(at -0.40005 0 270)
			(size 0 0)
			(layers "B.Cu" "B.Mask" "B.Paste")
			(net "PWRGD_FAIL_CPU0_EF_R1")
		)
	)
	(footprint ""
		(layer "B.Cu")
		(at 209.770218 -193.09461)
		(property "Reference" "C542"
			(at 0 0 0)
			(layer "B.SilkS")
			(hide yes)
			(effects
				(font
					(size 1.27 1.27)
				)
				(justify mirror)
			)
		)
		(property "Value" ""
			(at 0 0 0)
			(layer "B.Fab")
			(effects
				(font
					(size 1.27 1.27)
				)
				(justify mirror)
			)
		)
		(duplicate_pad_numbers_are_jumpers no)
		(fp_line
			(start -0.7874 -0.4064)
			(end -0.7874 0.4064)
			(stroke
				(width 0.1524)
				(type default)
			)
			(layer "B.SilkS")
		)
		(fp_line
			(start -0.7874 0.4064)
			(end 0.7874 0.4064)
			(stroke
				(width 0.1524)
				(type default)
			)
			(layer "B.SilkS")
		)
		(fp_line
			(start 0.7874 -0.4064)
			(end -0.7874 -0.4064)
			(stroke
				(width 0.1524)
				(type default)
			)
			(layer "B.SilkS")
		)
		(fp_line
			(start 0.7874 0.4064)
			(end 0.7874 -0.4064)
			(stroke
				(width 0.1524)
				(type default)
			)
			(layer "B.SilkS")
		)
		(fp_line
			(start -0.67945 -0.3048)
			(end -0.67945 0.3048)
			(stroke
				(width 0.1)
				(type default)
			)
			(layer "B.Fab")
		)
		(fp_line
			(start -0.67945 0.3048)
			(end -0.120396 0.3048)
			(stroke
				(width 0.1)
				(type default)
			)
			(layer "B.Fab")
		)
		(fp_line
			(start -0.12065 -0.3048)
			(end -0.67945 -0.3048)
			(stroke
				(width 0.1)
				(type default)
			)
			(layer "B.Fab")
		)
		(fp_line
			(start -0.12065 -0.2794)
			(end -0.12065 -0.3048)
			(stroke
				(width 0.1)
				(type default)
			)
			(layer "B.Fab")
		)
		(fp_line
			(start -0.120396 0.2794)
			(end 0.12065 0.2794)
			(stroke
				(width 0.1)
				(type default)
			)
			(layer "B.Fab")
		)
		(fp_line
			(start -0.120396 0.3048)
			(end -0.120396 0.2794)
			(stroke
				(width 0.1)
				(type default)
			)
			(layer "B.Fab")
		)
		(fp_line
			(start 0.12065 -0.305054)
			(end 0.12065 -0.2794)
			(stroke
				(width 0.1)
				(type default)
			)
			(layer "B.Fab")
		)
		(fp_line
			(start 0.12065 -0.2794)
			(end -0.12065 -0.2794)
			(stroke
				(width 0.1)
				(type default)
			)
			(layer "B.Fab")
		)
		(fp_line
			(start 0.12065 0.2794)
			(end 0.12065 0.3048)
			(stroke
				(width 0.1)
				(type default)
			)
			(layer "B.Fab")
		)
		(fp_line
			(start 0.12065 0.3048)
			(end 0.67945 0.3048)
			(stroke
				(width 0.1)
				(type default)
			)
			(layer "B.Fab")
		)
		(fp_line
			(start 0.67945 -0.305054)
			(end 0.12065 -0.305054)
			(stroke
				(width 0.1)
				(type default)
			)
			(layer "B.Fab")
		)
		(fp_line
			(start 0.67945 0.3048)
			(end 0.67945 -0.305054)
			(stroke
				(width 0.1)
				(type default)
			)
			(layer "B.Fab")
		)
		(pad "1" smd circle
			(at 0.40005 0 180)
			(size 0 0)
			(layers "B.Cu" "B.Mask" "B.Paste")
			(net "P3V3_AUX")
		)
		(pad "2" smd circle
			(at -0.40005 0 180)
			(size 0 0)
			(layers "B.Cu" "B.Mask" "B.Paste")
			(net "GND")
		)
	)
)
